(kicad_pcb
	(version 20260206)
	(generator "pcbnew")
	(generator_version "10.0")
	(general
		(thickness 1.6)
		(legacy_teardrops no)
	)
	(paper "A4")
	(title_block
		(title "9054_F0T_PDB_BD_GPU_F_V04_1213_1550_OCP.brd")
		(comment 1 "Grand Teton / footprints 304-310 of 608")
	)
	(layers
		(0 "F.Cu" signal "TOP")
		(4 "In1.Cu" signal "GND")
		(6 "In2.Cu" signal "IN1")
		(8 "In3.Cu" signal "GND1")
		(10 "In4.Cu" signal "VCC")
		(12 "In5.Cu" signal "VCC1")
		(14 "In6.Cu" signal "GND2")
		(16 "In7.Cu" signal "IN2")
		(18 "In8.Cu" signal "GND3")
		(2 "B.Cu" signal "BOTTOM")
		(9 "F.Adhes" user "F.Adhesive")
		(11 "B.Adhes" user "B.Adhesive")
		(13 "F.Paste" user "Package Geometry/Pastemask Top")
		(15 "B.Paste" user "Package Geometry/Pastemask Bottom")
		(5 "F.SilkS" user "Ref Des/Silkscreen Top")
		(7 "B.SilkS" user "Ref Des/Silkscreen Bottom")
		(1 "F.Mask" user "Board Geometry/Soldermask Top")
		(3 "B.Mask" user "Board Geometry/Soldermask Bottom")
		(17 "Dwgs.User" user "User.Drawings")
		(19 "Cmts.User" user "User.Comments")
		(21 "Eco1.User" user "User.Eco1")
		(23 "Eco2.User" user "User.Eco2")
		(25 "Edge.Cuts" user "Board Geometry/Outline")
		(27 "Margin" user)
		(31 "F.CrtYd" user "Package Geometry/Place Bound Top")
		(29 "B.CrtYd" user "Package Geometry/Place Bound Bottom")
		(35 "F.Fab" user "Ref Des/Assembly Top")
		(33 "B.Fab" user "Ref Des/Assembly Bottom")
	)
	(footprint ""
		(layer "F.Cu")
		(at 435.991 -41.148 -90)
		(property "Reference" "R1"
			(at 0 0 270)
			(layer "F.SilkS")
			(hide yes)
			(effects
				(font
					(size 1.27 1.27)
				)
			)
		)
		(property "Value" ""
			(at 0 0 270)
			(layer "F.Fab")
			(effects
				(font
					(size 1.27 1.27)
				)
			)
		)
		(duplicate_pad_numbers_are_jumpers no)
		(fp_line
			(start -0.7874 0.4064)
			(end -0.7874 -0.4064)
			(stroke
				(width 0.1524)
				(type default)
			)
			(layer "F.SilkS")
		)
		(fp_line
			(start 0.7874 0.4064)
			(end -0.7874 0.4064)
			(stroke
				(width 0.1524)
				(type default)
			)
			(layer "F.SilkS")
		)
		(fp_line
			(start -0.7874 -0.4064)
			(end 0.7874 -0.4064)
			(stroke
				(width 0.1524)
				(type default)
			)
			(layer "F.SilkS")
		)
		(fp_line
			(start 0.7874 -0.4064)
			(end 0.7874 0.4064)
			(stroke
				(width 0.1524)
				(type default)
			)
			(layer "F.SilkS")
		)
		(fp_line
			(start -0.67945 0.3048)
			(end -0.67945 -0.305054)
			(stroke
				(width 0.1)
				(type default)
			)
			(layer "F.Fab")
		)
		(fp_line
			(start -0.12065 0.3048)
			(end -0.67945 0.3048)
			(stroke
				(width 0.1)
				(type default)
			)
			(layer "F.Fab")
		)
		(fp_line
			(start 0.120396 0.3048)
			(end 0.120396 0.2794)
			(stroke
				(width 0.1)
				(type default)
			)
			(layer "F.Fab")
		)
		(fp_line
			(start 0.67945 0.3048)
			(end 0.120396 0.3048)
			(stroke
				(width 0.1)
				(type default)
			)
			(layer "F.Fab")
		)
		(fp_line
			(start -0.12065 0.2794)
			(end -0.12065 0.3048)
			(stroke
				(width 0.1)
				(type default)
			)
			(layer "F.Fab")
		)
		(fp_line
			(start 0.120396 0.2794)
			(end -0.12065 0.2794)
			(stroke
				(width 0.1)
				(type default)
			)
			(layer "F.Fab")
		)
		(fp_line
			(start -0.12065 -0.2794)
			(end 0.12065 -0.2794)
			(stroke
				(width 0.1)
				(type default)
			)
			(layer "F.Fab")
		)
		(fp_line
			(start 0.12065 -0.2794)
			(end 0.12065 -0.3048)
			(stroke
				(width 0.1)
				(type default)
			)
			(layer "F.Fab")
		)
		(fp_line
			(start 0.12065 -0.3048)
			(end 0.67945 -0.3048)
			(stroke
				(width 0.1)
				(type default)
			)
			(layer "F.Fab")
		)
		(fp_line
			(start 0.67945 -0.3048)
			(end 0.67945 0.3048)
			(stroke
				(width 0.1)
				(type default)
			)
			(layer "F.Fab")
		)
		(fp_line
			(start -0.67945 -0.305054)
			(end -0.12065 -0.305054)
			(stroke
				(width 0.1)
				(type default)
			)
			(layer "F.Fab")
		)
		(fp_line
			(start -0.12065 -0.305054)
			(end -0.12065 -0.2794)
			(stroke
				(width 0.1)
				(type default)
			)
			(layer "F.Fab")
		)
		(pad "1" smd circle
			(at -0.40005 0 270)
			(size 0 0)
			(layers "F.Cu" "F.Mask" "F.Paste")
			(net "SMB_PDB_MISC_SCL_R")
		)
		(pad "2" smd circle
			(at 0.40005 0 270)
			(size 0 0)
			(layers "F.Cu" "F.Mask" "F.Paste")
			(net "P3V3_AUX")
		)
	)
	(footprint ""
		(layer "F.Cu")
		(at 140.79982 -69.977 180)
		(property "Reference" "PR6984"
			(at 0 0 180)
			(layer "F.SilkS")
			(hide yes)
			(effects
				(font
					(size 1.27 1.27)
				)
			)
		)
		(property "Value" ""
			(at 0 0 180)
			(layer "F.Fab")
			(effects
				(font
					(size 1.27 1.27)
				)
			)
		)
		(duplicate_pad_numbers_are_jumpers no)
		(fp_line
			(start 1.2954 0.5842)
			(end -1.2954 0.5842)
			(stroke
				(width 0.1524)
				(type default)
			)
			(layer "F.SilkS")
		)
		(fp_line
			(start 1.2954 -0.5842)
			(end 1.2954 0.5842)
			(stroke
				(width 0.1524)
				(type default)
			)
			(layer "F.SilkS")
		)
		(fp_line
			(start -1.2954 0.5842)
			(end -1.2954 -0.5842)
			(stroke
				(width 0.1524)
				(type default)
			)
			(layer "F.SilkS")
		)
		(fp_line
			(start -1.2954 -0.5842)
			(end 1.2954 -0.5842)
			(stroke
				(width 0.1524)
				(type default)
			)
			(layer "F.SilkS")
		)
		(fp_line
			(start 1.1938 0.4064)
			(end 0.8636 0.4064)
			(stroke
				(width 0.1)
				(type default)
			)
			(layer "F.Fab")
		)
		(fp_line
			(start 1.1938 -0.406654)
			(end 1.1938 0.4064)
			(stroke
				(width 0.1)
				(type default)
			)
			(layer "F.Fab")
		)
		(fp_line
			(start 0.8636 0.4572)
			(end -0.8636 0.4572)
			(stroke
				(width 0.1)
				(type default)
			)
			(layer "F.Fab")
		)
		(fp_line
			(start 0.8636 0.4064)
			(end 0.8636 0.4572)
			(stroke
				(width 0.1)
				(type default)
			)
			(layer "F.Fab")
		)
		(fp_line
			(start 0.8636 -0.406654)
			(end 1.1938 -0.406654)
			(stroke
				(width 0.1)
				(type default)
			)
			(layer "F.Fab")
		)
		(fp_line
			(start 0.8636 -0.4572)
			(end 0.8636 -0.406654)
			(stroke
				(width 0.1)
				(type default)
			)
			(layer "F.Fab")
		)
		(fp_line
			(start -0.8636 0.4572)
			(end -0.8636 0.4318)
			(stroke
				(width 0.1)
				(type default)
			)
			(layer "F.Fab")
		)
		(fp_line
			(start -0.8636 0.4318)
			(end -0.8636 0.4064)
			(stroke
				(width 0.1)
				(type default)
			)
			(layer "F.Fab")
		)
		(fp_line
			(start -0.8636 0.4064)
			(end -1.1938 0.4064)
			(stroke
				(width 0.1)
				(type default)
			)
			(layer "F.Fab")
		)
		(fp_line
			(start -0.8636 -0.406654)
			(end -0.8636 -0.4572)
			(stroke
				(width 0.1)
				(type default)
			)
			(layer "F.Fab")
		)
		(fp_line
			(start -0.8636 -0.4572)
			(end 0.8636 -0.4572)
			(stroke
				(width 0.1)
				(type default)
			)
			(layer "F.Fab")
		)
		(fp_line
			(start -1.1938 0.4064)
			(end -1.1938 -0.406654)
			(stroke
				(width 0.1)
				(type default)
			)
			(layer "F.Fab")
		)
		(fp_line
			(start -1.1938 -0.406654)
			(end -0.8636 -0.406654)
			(stroke
				(width 0.1)
				(type default)
			)
			(layer "F.Fab")
		)
		(pad "1" smd rect
			(at -0.7366 0 90)
			(size 0.7112 0.8128)
			(layers "F.Cu" "F.Mask" "F.Paste")
			(net "P52V_HS2_4287_ADC_N")
		)
		(pad "2" smd rect
			(at 0.7366 0 90)
			(size 0.7112 0.8128)
			(layers "F.Cu" "F.Mask" "F.Paste")
			(net "P52V_HS2_SENSE_N_R1")
		)
	)
	(footprint ""
		(layer "F.Cu")
		(at 33.85439 -32.385 180)
		(property "Reference" "R47"
			(at 0 0 180)
			(layer "F.SilkS")
			(hide yes)
			(effects
				(font
					(size 1.27 1.27)
				)
			)
		)
		(property "Value" ""
			(at 0 0 180)
			(layer "F.Fab")
			(effects
				(font
					(size 1.27 1.27)
				)
			)
		)
		(duplicate_pad_numbers_are_jumpers no)
		(fp_line
			(start 2.234946 0.9271)
			(end -2.234946 0.9271)
			(stroke
				(width 0.1524)
				(type default)
			)
			(layer "F.SilkS")
		)
		(fp_line
			(start 2.234946 -0.9271)
			(end 2.234946 0.9271)
			(stroke
				(width 0.1524)
				(type default)
			)
			(layer "F.SilkS")
		)
		(fp_line
			(start -2.234946 0.9271)
			(end -2.234946 -0.9271)
			(stroke
				(width 0.1524)
				(type default)
			)
			(layer "F.SilkS")
		)
		(fp_line
			(start -2.234946 -0.9271)
			(end 2.234946 -0.9271)
			(stroke
				(width 0.1524)
				(type default)
			)
			(layer "F.SilkS")
		)
		(fp_line
			(start 1.575054 0.824992)
			(end 1.575054 -0.824992)
			(stroke
				(width 0.1)
				(type default)
			)
			(layer "F.Fab")
		)
		(fp_line
			(start 1.575054 -0.824992)
			(end -1.575054 -0.824992)
			(stroke
				(width 0.1)
				(type default)
			)
			(layer "F.Fab")
		)
		(fp_line
			(start -1.575054 0.824992)
			(end 1.575054 0.824992)
			(stroke
				(width 0.1)
				(type default)
			)
			(layer "F.Fab")
		)
		(fp_line
			(start -1.575054 -0.824992)
			(end -1.575054 0.824992)
			(stroke
				(width 0.1)
				(type default)
			)
			(layer "F.Fab")
		)
		(pad "1" smd rect
			(at -1.599946 0 180)
			(size 1.016 1.6002)
			(layers "F.Cu" "F.Mask" "F.Paste")
			(net "LED_D2_R4")
		)
		(pad "2" smd rect
			(at 1.599946 0 180)
			(size 1.016 1.6002)
			(layers "F.Cu" "F.Mask" "F.Paste")
			(net "LED_D2_R5")
		)
	)
	(footprint ""
		(layer "F.Cu")
		(at 378.079 -139.7)
		(property "Reference" "PC28"
			(at 4.4704 -5.18033 0)
			(unlocked yes)
			(layer "F.SilkS")
			(effects
				(font
					(size 0.7874 0.5842)
					(thickness 0.1524)
				)
				(justify left)
			)
		)
		(property "Value" ""
			(at 0 0 0)
			(layer "F.Fab")
			(effects
				(font
					(size 1.27 1.27)
				)
			)
		)
		(duplicate_pad_numbers_are_jumpers no)
		(fp_line
			(start -9.253728 3.750056)
			(end 9.249918 3.750056)
			(stroke
				(width 0.1524)
				(type default)
			)
			(layer "F.SilkS")
		)
		(fp_line
			(start 0 3.750056)
			(end -9.253728 3.750056)
			(stroke
				(width 0.1524)
				(type default)
			)
			(layer "F.SilkS")
		)
		(fp_circle
			(center 0 3.750056)
			(end 9.249918 3.750056)
			(stroke
				(width 0.1524)
				(type default)
			)
			(fill no)
			(layer "F.SilkS")
		)
		(fp_poly
			(pts
				(arc
					(start 9.249918 3.750056)
					(mid 0 12.999974)
					(end -9.249918 3.750056)
				)
			)
			(stroke
				(width 0)
				(type default)
			)
			(fill yes)
			(layer "F.SilkS")
		)
		(fp_circle
			(center 0 3.750056)
			(end 9.249918 3.750056)
			(stroke
				(width 0.1)
				(type default)
			)
			(fill no)
			(layer "F.Fab")
		)
		(pad "1" thru_hole rect
			(at 0 0)
			(size 1.778 1.778)
			(drill 1.27)
			(layers "*.Cu" "*.Mask")
			(remove_unused_layers no)
			(net "P52V_HS1")
			(clearance 0)
			(padstack
				(mode front_inner_back)
				(layer "Inner"
					(shape circle)
					(size 1.778 1.778)
					(clearance 0)
				)
				(layer "B.Cu"
					(shape rect)
					(size 1.778 1.778)
					(clearance 0)
				)
			)
		)
		(pad "2" thru_hole circle
			(at 0 7.500112)
			(size 1.778 1.778)
			(drill 1.27)
			(layers "*.Cu" "*.Mask")
			(remove_unused_layers no)
			(net "GND")
			(clearance 0)
		)
	)
	(footprint ""
		(layer "F.Cu")
		(at 171.831 -84.709 90)
		(property "Reference" "R5907"
			(at 0 0 90)
			(layer "F.SilkS")
			(hide yes)
			(effects
				(font
					(size 1.27 1.27)
				)
			)
		)
		(property "Value" ""
			(at 0 0 90)
			(layer "F.Fab")
			(effects
				(font
					(size 1.27 1.27)
				)
			)
		)
		(duplicate_pad_numbers_are_jumpers no)
		(fp_line
			(start 0.7874 -0.4064)
			(end 0.7874 0.4064)
			(stroke
				(width 0.1524)
				(type default)
			)
			(layer "F.SilkS")
		)
		(fp_line
			(start -0.7874 -0.4064)
			(end 0.7874 -0.4064)
			(stroke
				(width 0.1524)
				(type default)
			)
			(layer "F.SilkS")
		)
		(fp_line
			(start 0.7874 0.4064)
			(end -0.7874 0.4064)
			(stroke
				(width 0.1524)
				(type default)
			)
			(layer "F.SilkS")
		)
		(fp_line
			(start -0.7874 0.4064)
			(end -0.7874 -0.4064)
			(stroke
				(width 0.1524)
				(type default)
			)
			(layer "F.SilkS")
		)
		(fp_line
			(start -0.12065 -0.305054)
			(end -0.12065 -0.2794)
			(stroke
				(width 0.1)
				(type default)
			)
			(layer "F.Fab")
		)
		(fp_line
			(start -0.67945 -0.305054)
			(end -0.12065 -0.305054)
			(stroke
				(width 0.1)
				(type default)
			)
			(layer "F.Fab")
		)
		(fp_line
			(start 0.67945 -0.3048)
			(end 0.67945 0.3048)
			(stroke
				(width 0.1)
				(type default)
			)
			(layer "F.Fab")
		)
		(fp_line
			(start 0.12065 -0.3048)
			(end 0.67945 -0.3048)
			(stroke
				(width 0.1)
				(type default)
			)
			(layer "F.Fab")
		)
		(fp_line
			(start 0.12065 -0.2794)
			(end 0.12065 -0.3048)
			(stroke
				(width 0.1)
				(type default)
			)
			(layer "F.Fab")
		)
		(fp_line
			(start -0.12065 -0.2794)
			(end 0.12065 -0.2794)
			(stroke
				(width 0.1)
				(type default)
			)
			(layer "F.Fab")
		)
		(fp_line
			(start 0.120396 0.2794)
			(end -0.12065 0.2794)
			(stroke
				(width 0.1)
				(type default)
			)
			(layer "F.Fab")
		)
		(fp_line
			(start -0.12065 0.2794)
			(end -0.12065 0.3048)
			(stroke
				(width 0.1)
				(type default)
			)
			(layer "F.Fab")
		)
		(fp_line
			(start 0.67945 0.3048)
			(end 0.120396 0.3048)
			(stroke
				(width 0.1)
				(type default)
			)
			(layer "F.Fab")
		)
		(fp_line
			(start 0.120396 0.3048)
			(end 0.120396 0.2794)
			(stroke
				(width 0.1)
				(type default)
			)
			(layer "F.Fab")
		)
		(fp_line
			(start -0.12065 0.3048)
			(end -0.67945 0.3048)
			(stroke
				(width 0.1)
				(type default)
			)
			(layer "F.Fab")
		)
		(fp_line
			(start -0.67945 0.3048)
			(end -0.67945 -0.305054)
			(stroke
				(width 0.1)
				(type default)
			)
			(layer "F.Fab")
		)
		(pad "1" smd circle
			(at -0.40005 0 90)
			(size 0 0)
			(layers "F.Cu" "F.Mask" "F.Paste")
			(net "P3V3_2_AND")
		)
		(pad "2" smd circle
			(at 0.40005 0 90)
			(size 0 0)
			(layers "F.Cu" "F.Mask" "F.Paste")
			(net "GND")
		)
	)
	(footprint ""
		(layer "F.Cu")
		(at 61.92139 -99.06)
		(property "Reference" "PC39"
			(at -8.17499 -5.05333 0)
			(unlocked yes)
			(layer "F.SilkS")
			(effects
				(font
					(size 0.7874 0.5842)
					(thickness 0.1524)
				)
				(justify left)
			)
		)
		(property "Value" ""
			(at 0 0 0)
			(layer "F.Fab")
			(effects
				(font
					(size 1.27 1.27)
				)
			)
		)
		(duplicate_pad_numbers_are_jumpers no)
		(fp_line
			(start -9.253728 3.750056)
			(end 9.249918 3.750056)
			(stroke
				(width 0.1524)
				(type default)
			)
			(layer "F.SilkS")
		)
		(fp_line
			(start 0 3.750056)
			(end -9.253728 3.750056)
			(stroke
				(width 0.1524)
				(type default)
			)
			(layer "F.SilkS")
		)
		(fp_circle
			(center 0 3.750056)
			(end 9.249918 3.750056)
			(stroke
				(width 0.1524)
				(type default)
			)
			(fill no)
			(layer "F.SilkS")
		)
		(fp_poly
			(pts
				(arc
					(start 9.249918 3.750056)
					(mid 0 12.999974)
					(end -9.249918 3.750056)
				)
			)
			(stroke
				(width 0)
				(type default)
			)
			(fill yes)
			(layer "F.SilkS")
		)
		(fp_circle
			(center 0 3.750056)
			(end 9.249918 3.750056)
			(stroke
				(width 0.1)
				(type default)
			)
			(fill no)
			(layer "F.Fab")
		)
		(pad "1" thru_hole rect
			(at 0 0)
			(size 1.778 1.778)
			(drill 1.27)
			(layers "*.Cu" "*.Mask")
			(remove_unused_layers no)
			(net "P52V_HS2")
			(clearance 0)
			(padstack
				(mode front_inner_back)
				(layer "Inner"
					(shape circle)
					(size 1.778 1.778)
					(clearance 0)
				)
				(layer "B.Cu"
					(shape rect)
					(size 1.778 1.778)
					(clearance 0)
				)
			)
		)
		(pad "2" thru_hole circle
			(at 0 7.500112)
			(size 1.778 1.778)
			(drill 1.27)
			(layers "*.Cu" "*.Mask")
			(remove_unused_layers no)
			(net "GND")
			(clearance 0)
		)
	)
	(footprint ""
		(layer "F.Cu")
		(at 124.483876 -63.373)
		(property "Reference" "PQ39"
			(at 8.913114 -3.609848 0)
			(unlocked yes)
			(layer "F.SilkS")
			(effects
				(font
					(size 0.7874 0.5842)
					(thickness 0.1524)
				)
				(justify left)
			)
		)
		(property "Value" ""
			(at 0 0 0)
			(layer "F.Fab")
			(effects
				(font
					(size 1.27 1.27)
				)
			)
		)
		(duplicate_pad_numbers_are_jumpers no)
		(fp_line
			(start -7.649972 -4.99999)
			(end -7.649972 -3.3274)
			(stroke
				(width 0.1524)
				(type default)
			)
			(layer "F.SilkS")
		)
		(fp_line
			(start -7.649972 -1.7526)
			(end -7.649972 1.7526)
			(stroke
				(width 0.1524)
				(type default)
			)
			(layer "F.SilkS")
		)
		(fp_line
			(start -7.649972 3.3274)
			(end -7.649972 4.99999)
			(stroke
				(width 0.1524)
				(type default)
			)
			(layer "F.SilkS")
		)
		(fp_line
			(start -7.649972 4.99999)
			(end 5.115814 4.99999)
			(stroke
				(width 0.1524)
				(type default)
			)
			(layer "F.SilkS")
		)
		(fp_line
			(start 5.115814 -4.99999)
			(end -7.649972 -4.99999)
			(stroke
				(width 0.1524)
				(type default)
			)
			(layer "F.SilkS")
		)
		(fp_line
			(start 7.630414 4.99999)
			(end 7.649972 4.99999)
			(stroke
				(width 0.1524)
				(type default)
			)
			(layer "F.SilkS")
		)
		(fp_line
			(start 7.649972 -4.99999)
			(end 7.630414 -4.99999)
			(stroke
				(width 0.1524)
				(type default)
			)
			(layer "F.SilkS")
		)
		(fp_line
			(start 7.649972 4.99999)
			(end 7.649972 -4.99999)
			(stroke
				(width 0.1524)
				(type default)
			)
			(layer "F.SilkS")
		)
		(fp_line
			(start -7.649972 -4.99999)
			(end -7.649972 4.99999)
			(stroke
				(width 0.1)
				(type default)
			)
			(layer "F.Fab")
		)
		(fp_line
			(start -7.649972 4.99999)
			(end 7.649972 4.99999)
			(stroke
				(width 0.1)
				(type default)
			)
			(layer "F.Fab")
		)
		(fp_line
			(start 7.649972 -4.99999)
			(end -7.649972 -4.99999)
			(stroke
				(width 0.1)
				(type default)
			)
			(layer "F.Fab")
		)
		(fp_line
			(start 7.649972 4.99999)
			(end 7.649972 -4.99999)
			(stroke
				(width 0.1)
				(type default)
			)
			(layer "F.Fab")
		)
		(pad "D" smd circle
			(at 2.15011 0)
			(size 0 0)
			(layers "F.Cu" "F.Mask" "F.Paste")
			(net "P52V_HS2_DRAIN_1")
		)
		(pad "G" smd rect
			(at -7.050024 -2.54 270)
			(size 1.3208 3.0988)
			(layers "F.Cu" "F.Mask" "F.Paste")
			(net "P52V_HS2_GATE2")
		)
		(pad "S" smd rect
			(at -7.050024 2.54 270)
			(size 1.3208 3.0988)
			(layers "F.Cu" "F.Mask" "F.Paste")
			(net "P52V_HS2")
		)
		(zone
			(layer "F.Cu")
			(hatch none 0.5)
			(connect_pads
				(clearance 0)
			)
			(min_thickness 0.25)
			(keepout
				(tracks not_allowed)
				(vias allowed)
				(pads allowed)
				(copperpour not_allowed)
				(footprints allowed)
			)
			(placement
				(enabled no)
				(sheetname "")
			)
			(fill
				(thermal_gap 0.5)
				(thermal_bridge_width 0.5)
				(island_removal_mode 0)
			)
			(polygon
				(pts
					(xy 129.665476 -68.3514) (xy 116.838476 -68.3514) (xy 116.838476 -66.6242) (xy 119.048276 -66.6242)
					(xy 119.048276 -65.2018) (xy 116.838476 -65.2018) (xy 116.838476 -61.5442) (xy 119.048276 -61.5442)
					(xy 119.048276 -60.1218) (xy 116.838476 -60.1218) (xy 116.838476 -58.3946) (xy 129.665476 -58.3946)
					(xy 129.665476 -59.563) (xy 123.467876 -59.563) (xy 123.467876 -67.183) (xy 129.665476 -67.183)
				)
			)
		)
	)
)
